FILE_TYPE = MACRO_DRAWING;
SET COLOR_WIRE YELLOW;
SET COLOR_PROP ORANGE;
SET COLOR_DOT WHITE;
SET COLOR_ARC YELLOW;
SET COLOR_BODY GREEN;
SET COLOR_NOTE PURPLE;
SET PROP_DISPLAY VALUE;
SET PAGE_NUMBER P7;
FORCEADD OFFPAGE_IN..1
(-11750 8950);
FORCEPROP 1 LAST BODY_TYPE COMMENT
J 0
(-11740 9085);
DISPLAY 0.808511 (-11740 9085);
PAINT GREEN (-11740 9085);
DISPLAY INVISIBLE (-11740 9085);
FORCEPROP 1 LAST OFFPAGE TRUE
J 0
(-11740 9005);
DISPLAY 0.808511 (-11740 9005);
PAINT GREEN (-11740 9005);
DISPLAY INVISIBLE (-11740 9005);
FORCEPROP 2 LAST PATH I1
J 0
(-11900 9000);
DISPLAY 1.021277 (-11900 9000);
DISPLAY INVISIBLE (-11900 9000);
FORCEPROP 1 LAST CDS_LMAN_SYM_OUTLINE -50,50,50,-50
J 0
(-11750 8950);
DISPLAY 0.468085 (-11750 8950);
PAINT GREEN (-11750 8950);
DISPLAY INVISIBLE (-11750 8950);
FORCEPROP 2 LAST CDS_LIB cls
J 0
(-11750 8950);
DISPLAY INVISIBLE (-11750 8950);
FORCEPROP 2 LAST $XR0 16D12> 
J 0
(-11964 8950);
DISPLAY 0.638298 (-11964 8950);
PAINT MONO (-11964 8950);
FORCEADD RESISTOR..1
(-9300 8950);
FORCEPROP 1 LAST $LOCATION R67
J 2
(-9450 8950);
DISPLAY 1.212766 (-9450 8950);
PAINT GREEN (-9450 8950);
FORCEPROP 0 LAST CDS_LOCATION R67
J 0
(-9100 9050);
DISPLAY 1.021277 (-9100 9050);
DISPLAY INVISIBLE (-9100 9050);
FORCEPROP 0 LAST $SEC 1
J 0
(-9100 9050);
DISPLAY 0.680851 (-9100 9050);
PAINT MONO (-9100 9050);
DISPLAY INVISIBLE (-9100 9050);
FORCEPROP 0 LAST CDS_SEC 1
J 0
(-9100 9050);
DISPLAY 1.021277 (-9100 9050);
DISPLAY INVISIBLE (-9100 9050);
FORCEPROP 0 LASTPIN (-9400 8950) $PN 1
J 2
(-9410 8960);
DISPLAY 0.680851 (-9410 8960);
PAINT MONO (-9410 8960);
FORCEPROP 0 LASTPIN (-9150 8950) $PN 2
J 0
(-9140 8960);
DISPLAY 0.680851 (-9140 8960);
PAINT MONO (-9140 8960);
FORCEPROP 1 LAST VALUE 33OHM
J 0
(-9100 8950);
DISPLAY 1.234043 (-9100 8950);
PAINT GREEN (-9100 8950);
FORCEPROP 0 LAST PACKAGE 0402
J 0
(-9350 8850);
DISPLAY 1.021277 (-9350 8850);
FORCEPROP 1 LAST PATH I13
J 0
(-9497 9055);
DISPLAY 1.212766 (-9497 9055);
PAINT GREEN (-9497 9055);
DISPLAY INVISIBLE (-9497 9055);
FORCEPROP 1 LAST TOLERANCE 1%
J 0
(-9497 9205);
DISPLAY 1.212766 (-9497 9205);
PAINT GREEN (-9497 9205);
DISPLAY INVISIBLE (-9497 9205);
FORCEPROP 1 LAST CLS_PN G155-133R0-01
J 0
(-9436 9150);
DISPLAY 1.212766 (-9436 9150);
PAINT GREEN (-9436 9150);
DISPLAY INVISIBLE (-9436 9150);
FORCEPROP 2 LAST CDS_LIB passive
J 0
(-9300 8950);
DISPLAY INVISIBLE (-9300 8950);
FORCEPROP 1 LAST CDS_LMAN_SYM_OUTLINE -50,50,100,-50
J 0
(-9300 8950);
DISPLAY 0.468085 (-9300 8950);
PAINT GREEN (-9300 8950);
DISPLAY INVISIBLE (-9300 8950);
FORCEPROP 2 LAST SIGNAL_MODEL DEFAULT_RESISTOR_33OHM_2_1
J 0
(-9450 9150);
DISPLAY 1.021277 (-9450 9150);
DISPLAY INVISIBLE (-9450 9150);
FORCEADD RESISTOR..1
(-9300 9050);
FORCEPROP 1 LAST $LOCATION R66
J 2
(-9450 9050);
DISPLAY 1.212766 (-9450 9050);
PAINT GREEN (-9450 9050);
FORCEPROP 0 LAST CDS_LOCATION R66
J 0
(-9100 9150);
DISPLAY 1.021277 (-9100 9150);
DISPLAY INVISIBLE (-9100 9150);
FORCEPROP 0 LAST $SEC 1
J 0
(-9100 9150);
DISPLAY 0.680851 (-9100 9150);
PAINT MONO (-9100 9150);
DISPLAY INVISIBLE (-9100 9150);
FORCEPROP 0 LAST CDS_SEC 1
J 0
(-9100 9150);
DISPLAY 1.021277 (-9100 9150);
DISPLAY INVISIBLE (-9100 9150);
FORCEPROP 0 LASTPIN (-9400 9050) $PN 1
J 2
(-9410 9060);
DISPLAY 0.680851 (-9410 9060);
PAINT MONO (-9410 9060);
FORCEPROP 0 LASTPIN (-9150 9050) $PN 2
J 0
(-9140 9060);
DISPLAY 0.680851 (-9140 9060);
PAINT MONO (-9140 9060);
FORCEPROP 1 LAST VALUE 33OHM
J 0
(-9100 9050);
DISPLAY 1.234043 (-9100 9050);
PAINT GREEN (-9100 9050);
FORCEPROP 0 LAST PACKAGE 0402
J 0
(-9350 9100);
DISPLAY 1.021277 (-9350 9100);
FORCEPROP 1 LAST PATH I14
J 0
(-9497 9155);
DISPLAY 1.212766 (-9497 9155);
PAINT GREEN (-9497 9155);
DISPLAY INVISIBLE (-9497 9155);
FORCEPROP 1 LAST TOLERANCE 1%
J 0
(-9497 9305);
DISPLAY 1.212766 (-9497 9305);
PAINT GREEN (-9497 9305);
DISPLAY INVISIBLE (-9497 9305);
FORCEPROP 1 LAST CLS_PN G155-133R0-01
J 0
(-9436 9250);
DISPLAY 1.212766 (-9436 9250);
PAINT GREEN (-9436 9250);
DISPLAY INVISIBLE (-9436 9250);
FORCEPROP 2 LAST SIGNAL_MODEL DEFAULT_RESISTOR_33OHM_2_1
J 0
(-9450 9250);
DISPLAY 1.021277 (-9450 9250);
DISPLAY INVISIBLE (-9450 9250);
FORCEPROP 1 LAST CDS_LMAN_SYM_OUTLINE -50,50,100,-50
J 0
(-9300 9050);
DISPLAY 0.468085 (-9300 9050);
PAINT GREEN (-9300 9050);
DISPLAY INVISIBLE (-9300 9050);
FORCEPROP 2 LAST CDS_LIB passive
J 0
(-9300 9050);
DISPLAY INVISIBLE (-9300 9050);
FORCEADD VCC..1
(-10450 10000);
FORCEPROP 3 LASTPIN (-10400 9950) SIG_NAME XP3R3V_FPGA\g
J 0
(-10390 9960);
DISPLAY 0.659574 (-10390 9960);
PAINT MONO (-10390 9960);
DISPLAY INVISIBLE (-10390 9960);
FORCEPROP 1 LAST HDL_POWER XP3R3V_FPGA
J 1
(-10395 10055);
DISPLAY 1.021277 (-10395 10055);
PAINT GREEN (-10395 10055);
FORCEPROP 0 LAST VOLTAGE 3.3V
J 0
(-10700 10150);
DISPLAY 1.021277 (-10700 10150);
DISPLAY BOTH (-10700 10150);
FORCEPROP 1 LAST PATH I15
J 0
(-10415 10090);
DISPLAY 0.808511 (-10415 10090);
PAINT GREEN (-10415 10090);
DISPLAY INVISIBLE (-10415 10090);
FORCEPROP 1 LAST BODY_TYPE PLUMBING
J 0
(-10495 9957);
DISPLAY 0.340426 (-10495 9957);
PAINT GREEN (-10495 9957);
DISPLAY INVISIBLE (-10495 9957);
FORCEPROP 1 LAST CDS_LMAN_SYM_OUTLINE -250,250,250,-250
J 0
(-10450 10000);
DISPLAY 0.468085 (-10450 10000);
PAINT GREEN (-10450 10000);
DISPLAY INVISIBLE (-10450 10000);
FORCEPROP 2 LAST CDS_LIB cls
J 0
(-10450 10000);
DISPLAY INVISIBLE (-10450 10000);
FORCEADD VCC..1
(-9150 8450);
FORCEPROP 3 LASTPIN (-9100 8400) SIG_NAME XP3R3V_FPGA\g
J 0
(-9090 8410);
DISPLAY 0.659574 (-9090 8410);
PAINT MONO (-9090 8410);
DISPLAY INVISIBLE (-9090 8410);
FORCEPROP 1 LAST HDL_POWER XP3R3V_FPGA
J 1
(-9095 8505);
DISPLAY 1.021277 (-9095 8505);
PAINT GREEN (-9095 8505);
FORCEPROP 0 LAST VOLTAGE 3.3V
J 0
(-9400 8600);
DISPLAY 1.021277 (-9400 8600);
DISPLAY BOTH (-9400 8600);
FORCEPROP 1 LAST PATH I17
J 0
(-9115 8540);
DISPLAY 0.808511 (-9115 8540);
PAINT GREEN (-9115 8540);
DISPLAY INVISIBLE (-9115 8540);
FORCEPROP 1 LAST BODY_TYPE PLUMBING
J 0
(-9195 8407);
DISPLAY 0.340426 (-9195 8407);
PAINT GREEN (-9195 8407);
DISPLAY INVISIBLE (-9195 8407);
FORCEPROP 2 LAST CDS_LIB cls
J 0
(-9150 8450);
DISPLAY INVISIBLE (-9150 8450);
FORCEPROP 1 LAST CDS_LMAN_SYM_OUTLINE -250,250,250,-250
J 0
(-9150 8450);
DISPLAY 0.468085 (-9150 8450);
PAINT GREEN (-9150 8450);
DISPLAY INVISIBLE (-9150 8450);
FORCEADD CAPACITOR..2
R 2
(-4300 8750);
FORCEPROP 1 LAST $LOCATION C40
J 2
(-4050 8650);
DISPLAY 1.212766 (-4050 8650);
PAINT GREEN (-4050 8650);
FORCEPROP 0 LAST CDS_LOCATION C40
J 0
(-3900 8900);
DISPLAY 1.021277 (-3900 8900);
DISPLAY INVISIBLE (-3900 8900);
FORCEPROP 0 LAST $SEC 1
J 0
(-3900 8900);
DISPLAY 0.680851 (-3900 8900);
PAINT MONO (-3900 8900);
DISPLAY INVISIBLE (-3900 8900);
FORCEPROP 0 LAST CDS_SEC 1
J 0
(-3900 8900);
DISPLAY 1.021277 (-3900 8900);
DISPLAY INVISIBLE (-3900 8900);
FORCEPROP 0 LASTPIN (-4300 8850) $PN 1
R 1
J 0
(-4310 8860);
DISPLAY 0.680851 (-4310 8860);
PAINT MONO (-4310 8860);
FORCEPROP 0 LASTPIN (-4300 8600) $PN 2
R 1
J 2
(-4310 8590);
DISPLAY 0.680851 (-4310 8590);
PAINT MONO (-4310 8590);
FORCEPROP 0 LAST PACKAGE 0402
J 0
(-4200 8900);
DISPLAY 1.021277 (-4200 8900);
FORCEPROP 0 LAST VOLTAGE 25V
J 0
(-4200 8550);
DISPLAY 1.021277 (-4200 8550);
FORCEPROP 1 LAST VALUE 0.1UF
J 2
(-3900 8800);
DISPLAY 1.212766 (-3900 8800);
PAINT GREEN (-3900 8800);
FORCEPROP 1 LAST CLS_PN G105-0B104-EK
J 2
(-4200 8800);
DISPLAY 1.212766 (-4200 8800);
PAINT GREEN (-4200 8800);
DISPLAY INVISIBLE (-4200 8800);
FORCEPROP 1 LAST CDS_LMAN_SYM_OUTLINE -50,0,50,-50
J 2
(-4300 8750);
DISPLAY 0.468085 (-4300 8750);
PAINT GREEN (-4300 8750);
DISPLAY INVISIBLE (-4300 8750);
FORCEPROP 2 LAST CDS_LIB passive
J 0
(-4300 8750);
DISPLAY INVISIBLE (-4300 8750);
FORCEPROP 1 LAST TOLERANCE 10%
J 2
(-4150 8850);
DISPLAY 1.212766 (-4150 8850);
PAINT GREEN (-4150 8850);
DISPLAY INVISIBLE (-4150 8850);
FORCEPROP 1 LAST PATH I18
J 2
(-4200 8800);
DISPLAY 1.212766 (-4200 8800);
PAINT GREEN (-4200 8800);
DISPLAY INVISIBLE (-4200 8800);
FORCEADD CAPACITOR..2
R 2
(-5650 8750);
FORCEPROP 1 LAST $LOCATION C275
J 2
(-5400 8650);
DISPLAY 1.212766 (-5400 8650);
PAINT GREEN (-5400 8650);
FORCEPROP 0 LAST CDS_LOCATION C275
J 0
(-5700 8880);
DISPLAY 1.021277 (-5700 8880);
DISPLAY INVISIBLE (-5700 8880);
FORCEPROP 0 LAST $SEC 1
J 0
(-5700 8880);
DISPLAY 0.680851 (-5700 8880);
PAINT MONO (-5700 8880);
DISPLAY INVISIBLE (-5700 8880);
FORCEPROP 0 LAST CDS_SEC 1
J 0
(-5700 8880);
DISPLAY 1.021277 (-5700 8880);
DISPLAY INVISIBLE (-5700 8880);
FORCEPROP 0 LASTPIN (-5650 8850) $PN 1
R 1
J 0
(-5660 8860);
DISPLAY 0.680851 (-5660 8860);
PAINT MONO (-5660 8860);
FORCEPROP 0 LASTPIN (-5650 8600) $PN 2
R 1
J 2
(-5660 8590);
DISPLAY 0.680851 (-5660 8590);
PAINT MONO (-5660 8590);
FORCEPROP 0 LAST PACKAGE 0402
J 0
(-5550 8900);
DISPLAY 1.021277 (-5550 8900);
FORCEPROP 0 LAST VOLTAGE 25V
J 0
(-5550 8500);
DISPLAY 1.021277 (-5550 8500);
FORCEPROP 1 LAST VALUE 0.1UF
J 2
(-5300 8800);
DISPLAY 1.212766 (-5300 8800);
PAINT GREEN (-5300 8800);
FORCEPROP 1 LAST CLS_PN G105-0B104-EK
J 2
(-5550 8800);
DISPLAY 1.212766 (-5550 8800);
PAINT GREEN (-5550 8800);
DISPLAY INVISIBLE (-5550 8800);
FORCEPROP 1 LAST CDS_LMAN_SYM_OUTLINE -50,0,50,-50
J 2
(-5650 8750);
DISPLAY 0.468085 (-5650 8750);
PAINT GREEN (-5650 8750);
DISPLAY INVISIBLE (-5650 8750);
FORCEPROP 2 LAST CDS_LIB passive
J 0
(-5650 8750);
DISPLAY INVISIBLE (-5650 8750);
FORCEPROP 1 LAST TOLERANCE 10%
J 2
(-5500 8850);
DISPLAY 1.212766 (-5500 8850);
PAINT GREEN (-5500 8850);
DISPLAY INVISIBLE (-5500 8850);
FORCEPROP 1 LAST PATH I19
J 2
(-5550 8800);
DISPLAY 1.212766 (-5550 8800);
PAINT GREEN (-5550 8800);
DISPLAY INVISIBLE (-5550 8800);
FORCEADD OFFPAGE_BI..1
R 2
(-11750 9050);
FORCEPROP 2 LAST PATH I2
J 0
(-11950 9100);
DISPLAY 1.021277 (-11950 9100);
DISPLAY INVISIBLE (-11950 9100);
FORCEPROP 1 LAST OFFPAGE TRUE
J 2
(-11760 9105);
DISPLAY 0.808511 (-11760 9105);
PAINT GREEN (-11760 9105);
DISPLAY INVISIBLE (-11760 9105);
FORCEPROP 1 LAST BODY_TYPE COMMENT
J 2
(-11760 9185);
DISPLAY 0.808511 (-11760 9185);
PAINT GREEN (-11760 9185);
DISPLAY INVISIBLE (-11760 9185);
FORCEPROP 1 LAST CDS_LMAN_SYM_OUTLINE -50,50,50,-50
J 2
(-11750 9050);
DISPLAY 0.468085 (-11750 9050);
PAINT GREEN (-11750 9050);
DISPLAY INVISIBLE (-11750 9050);
FORCEPROP 2 LAST CDS_LIB cls
J 2
(-11750 9050);
DISPLAY INVISIBLE (-11750 9050);
FORCEPROP 2 LAST $XR0 16C12<> 
J 0
(-12000 9050);
DISPLAY 0.638298 (-12000 9050);
PAINT MONO (-12000 9050);
FORCEADD VCC..1
(-4050 9250);
FORCEPROP 3 LASTPIN (-4000 9200) SIG_NAME XP3R3V_FPGA\g
J 0
(-3990 9210);
DISPLAY 0.659574 (-3990 9210);
PAINT MONO (-3990 9210);
DISPLAY INVISIBLE (-3990 9210);
FORCEPROP 1 LAST HDL_POWER XP3R3V_FPGA
J 1
(-3995 9305);
DISPLAY 1.021277 (-3995 9305);
PAINT GREEN (-3995 9305);
FORCEPROP 0 LAST VOLTAGE 3.3V
J 0
(-4300 9400);
DISPLAY 1.021277 (-4300 9400);
DISPLAY BOTH (-4300 9400);
FORCEPROP 2 LAST CDS_LIB cls
J 0
(-4050 9250);
DISPLAY INVISIBLE (-4050 9250);
FORCEPROP 1 LAST CDS_LMAN_SYM_OUTLINE -250,250,250,-250
J 0
(-4050 9250);
DISPLAY 0.468085 (-4050 9250);
PAINT GREEN (-4050 9250);
DISPLAY INVISIBLE (-4050 9250);
FORCEPROP 1 LAST BODY_TYPE PLUMBING
J 0
(-4095 9207);
DISPLAY 0.340426 (-4095 9207);
PAINT GREEN (-4095 9207);
DISPLAY INVISIBLE (-4095 9207);
FORCEPROP 1 LAST PATH I20
J 0
(-4015 9340);
DISPLAY 0.808511 (-4015 9340);
PAINT GREEN (-4015 9340);
DISPLAY INVISIBLE (-4015 9340);
FORCEADD FERRITEBEAD..1
R 2
(-4650 9100);
FORCEPROP 1 LAST $LOCATION L17
J 0
(-5050 9100);
DISPLAY 1.212766 (-5050 9100);
PAINT GREEN (-5050 9100);
FORCEPROP 0 LAST CDS_LOCATION L17
J 0
(-4250 9200);
DISPLAY 1.021277 (-4250 9200);
DISPLAY INVISIBLE (-4250 9200);
FORCEPROP 0 LAST $SEC 1
J 0
(-4250 9200);
DISPLAY 0.680851 (-4250 9200);
PAINT MONO (-4250 9200);
DISPLAY INVISIBLE (-4250 9200);
FORCEPROP 0 LAST CDS_SEC 1
J 0
(-4250 9200);
DISPLAY 1.021277 (-4250 9200);
DISPLAY INVISIBLE (-4250 9200);
FORCEPROP 0 LASTPIN (-4550 9050) $PN 1
J 0
(-4540 9060);
DISPLAY 0.680851 (-4540 9060);
PAINT MONO (-4540 9060);
FORCEPROP 0 LASTPIN (-4950 9050) $PN 2
J 2
(-4960 9060);
DISPLAY 0.680851 (-4960 9060);
PAINT MONO (-4960 9060);
FORCEPROP 1 LAST VALUE 600OHM
J 2
(-4250 9100);
DISPLAY 1.212766 (-4250 9100);
PAINT GREEN (-4250 9100);
FORCEPROP 0 LAST PACKAGE 0603
J 0
(-4850 9150);
DISPLAY 1.021277 (-4850 9150);
FORCEPROP 2 LAST DCR 1300MA 0.15OHM
J 2
(-4350 8950);
FORCEPROP 2 LAST CDS_LIB passive
J 0
(-4650 9100);
DISPLAY INVISIBLE (-4650 9100);
FORCEPROP 1 LAST CDS_LMAN_SYM_OUTLINE 0,0,200,-100
J 2
(-4650 9100);
DISPLAY 0.468085 (-4650 9100);
PAINT GREEN (-4650 9100);
DISPLAY INVISIBLE (-4650 9100);
FORCEPROP 1 LAST CLS_PN G191-10097-01
J 0
(-4600 9150);
DISPLAY 1.212766 (-4600 9150);
PAINT GREEN (-4600 9150);
DISPLAY INVISIBLE (-4600 9150);
FORCEPROP 1 LAST PATH I21
J 0
(-4600 9150);
DISPLAY 1.212766 (-4600 9150);
PAINT GREEN (-4600 9150);
DISPLAY INVISIBLE (-4600 9150);
FORCEPROP 1 LAST TOLERANCE 25%
J 2
(-4550 9150);
DISPLAY 1.212766 (-4550 9150);
PAINT GREEN (-4550 9150);
DISPLAY INVISIBLE (-4550 9150);
FORCEADD GND_SG..1
R 2
(-5600 8200);
FORCEPROP 3 LASTPIN (-5650 8250) SIG_NAME SG\g
J 0
(-5640 8260);
DISPLAY 0.659574 (-5640 8260);
PAINT MONO (-5640 8260);
DISPLAY INVISIBLE (-5640 8260);
FORCEPROP 1 LAST HDL_POWER SG
J 1
(-5655 8105);
DISPLAY 0.808511 (-5655 8105);
PAINT GREEN (-5655 8105);
FORCEPROP 1 LAST CDS_LMAN_SYM_OUTLINE 0,0,100,-50
J 2
(-5600 8200);
DISPLAY 0.468085 (-5600 8200);
PAINT GREEN (-5600 8200);
DISPLAY INVISIBLE (-5600 8200);
FORCEPROP 2 LAST CDS_LIB cls
J 0
(-5600 8200);
DISPLAY INVISIBLE (-5600 8200);
FORCEPROP 1 LAST BODY_TYPE PLUMBING
J 2
(-5615 8185);
DISPLAY 0.808511 (-5615 8185);
PAINT GREEN (-5615 8185);
DISPLAY INVISIBLE (-5615 8185);
FORCEPROP 1 LAST PATH I22
J 2
(-5635 8200);
DISPLAY 0.808511 (-5635 8200);
PAINT GREEN (-5635 8200);
DISPLAY INVISIBLE (-5635 8200);
FORCEADD CAPACITOR..2
R 2
(-5200 8750);
FORCEPROP 1 LAST $LOCATION C274
J 2
(-4900 8700);
DISPLAY 1.212766 (-4900 8700);
PAINT GREEN (-4900 8700);
FORCEPROP 0 LAST CDS_LOCATION C274
J 0
(-5250 8900);
DISPLAY 1.021277 (-5250 8900);
DISPLAY INVISIBLE (-5250 8900);
FORCEPROP 0 LAST $SEC 1
J 0
(-5250 8900);
DISPLAY 0.680851 (-5250 8900);
PAINT MONO (-5250 8900);
DISPLAY INVISIBLE (-5250 8900);
FORCEPROP 0 LAST CDS_SEC 1
J 0
(-5250 8900);
DISPLAY 1.021277 (-5250 8900);
DISPLAY INVISIBLE (-5250 8900);
FORCEPROP 0 LASTPIN (-5200 8850) $PN 1
R 1
J 0
(-5210 8860);
DISPLAY 0.680851 (-5210 8860);
PAINT MONO (-5210 8860);
FORCEPROP 0 LASTPIN (-5200 8600) $PN 2
R 1
J 2
(-5210 8590);
DISPLAY 0.680851 (-5210 8590);
PAINT MONO (-5210 8590);
FORCEPROP 1 LAST VALUE 10UF
J 2
(-4900 8800);
DISPLAY 1.212766 (-4900 8800);
PAINT GREEN (-4900 8800);
FORCEPROP 0 LAST PACKAGE 0402
J 0
(-5100 8600);
DISPLAY 1.021277 (-5100 8600);
FORCEPROP 0 LAST VOLTAGE 6.3V
J 0
(-5100 8500);
DISPLAY 1.021277 (-5100 8500);
FORCEPROP 2 LAST CDS_LIB passive
J 0
(-5200 8750);
DISPLAY INVISIBLE (-5200 8750);
FORCEPROP 1 LAST CDS_LMAN_SYM_OUTLINE -50,0,50,-50
J 2
(-5200 8750);
DISPLAY 0.468085 (-5200 8750);
PAINT GREEN (-5200 8750);
DISPLAY INVISIBLE (-5200 8750);
FORCEPROP 1 LAST CLS_PN G105-0C106-BM
J 2
(-5100 8800);
DISPLAY 1.212766 (-5100 8800);
PAINT GREEN (-5100 8800);
DISPLAY INVISIBLE (-5100 8800);
FORCEPROP 1 LAST TOLERANCE 20%
J 2
(-5050 8850);
DISPLAY 1.212766 (-5050 8850);
PAINT GREEN (-5050 8850);
DISPLAY INVISIBLE (-5050 8850);
FORCEPROP 1 LAST PATH I23
J 2
(-5100 8800);
DISPLAY 1.212766 (-5100 8800);
PAINT GREEN (-5100 8800);
DISPLAY INVISIBLE (-5100 8800);
FORCEADD GND_SG..1
(-7950 8050);
FORCEPROP 3 LASTPIN (-7900 8100) SIG_NAME SG\g
J 0
(-7890 8110);
DISPLAY 0.659574 (-7890 8110);
PAINT MONO (-7890 8110);
DISPLAY INVISIBLE (-7890 8110);
FORCEPROP 1 LAST HDL_POWER SG
J 1
(-7895 7955);
DISPLAY 0.808511 (-7895 7955);
PAINT GREEN (-7895 7955);
FORCEPROP 1 LAST PATH I25
J 0
(-7915 8050);
DISPLAY 0.808511 (-7915 8050);
PAINT GREEN (-7915 8050);
DISPLAY INVISIBLE (-7915 8050);
FORCEPROP 1 LAST BODY_TYPE PLUMBING
J 0
(-7935 8035);
DISPLAY 0.808511 (-7935 8035);
PAINT GREEN (-7935 8035);
DISPLAY INVISIBLE (-7935 8035);
FORCEPROP 1 LAST CDS_LMAN_SYM_OUTLINE 0,0,100,-50
J 0
(-7950 8050);
DISPLAY 0.468085 (-7950 8050);
PAINT GREEN (-7950 8050);
DISPLAY INVISIBLE (-7950 8050);
FORCEPROP 2 LAST CDS_LIB cls
J 0
(-7950 8050);
DISPLAY INVISIBLE (-7950 8050);
FORCEADD RESISTOR..2
(-10400 9550);
FORCEPROP 1 LAST $LOCATION R64
J 0
(-10350 9400);
DISPLAY 1.212766 (-10350 9400);
PAINT GREEN (-10350 9400);
FORCEPROP 0 LAST CDS_LOCATION R64
J 0
(-10350 9650);
DISPLAY 1.021277 (-10350 9650);
DISPLAY INVISIBLE (-10350 9650);
FORCEPROP 0 LAST $SEC 1
J 0
(-10350 9650);
DISPLAY 0.680851 (-10350 9650);
PAINT MONO (-10350 9650);
DISPLAY INVISIBLE (-10350 9650);
FORCEPROP 0 LAST CDS_SEC 1
J 0
(-10350 9650);
DISPLAY 1.021277 (-10350 9650);
DISPLAY INVISIBLE (-10350 9650);
FORCEPROP 0 LASTPIN (-10400 9650) $PN 1
R 1
J 0
(-10410 9660);
DISPLAY 0.680851 (-10410 9660);
PAINT MONO (-10410 9660);
FORCEPROP 0 LASTPIN (-10400 9400) $PN 2
R 1
J 2
(-10410 9390);
DISPLAY 0.680851 (-10410 9390);
PAINT MONO (-10410 9390);
FORCEPROP 0 LAST PACKAGE 0402
J 0
(-10350 9700);
DISPLAY 1.021277 (-10350 9700);
FORCEPROP 1 LAST VALUE 4.7KOHM
J 0
(-10350 9600);
DISPLAY 0.978723 (-10350 9600);
PAINT GREEN (-10350 9600);
FORCEPROP 1 LAST PATH I3
J 0
(-10597 9655);
DISPLAY 1.212766 (-10597 9655);
PAINT GREEN (-10597 9655);
DISPLAY INVISIBLE (-10597 9655);
FORCEPROP 1 LAST TOLERANCE 1%
J 0
(-10597 9805);
DISPLAY 1.212766 (-10597 9805);
PAINT GREEN (-10597 9805);
DISPLAY INVISIBLE (-10597 9805);
FORCEPROP 1 LAST CLS_PN G155-14701-01
J 0
(-10536 9750);
DISPLAY 1.212766 (-10536 9750);
PAINT GREEN (-10536 9750);
DISPLAY INVISIBLE (-10536 9750);
FORCEPROP 1 LAST CDS_LMAN_SYM_OUTLINE -50,50,50,-100
J 0
(-10400 9550);
DISPLAY 0.468085 (-10400 9550);
PAINT GREEN (-10400 9550);
DISPLAY INVISIBLE (-10400 9550);
FORCEPROP 2 LAST CDS_LIB passive
J 0
(-10400 9550);
DISPLAY INVISIBLE (-10400 9550);
FORCEADD OFFPAGE_IN..1
R 2
(-2400 7050);
FORCEPROP 1 LAST BODY_TYPE COMMENT
J 2
(-2410 7185);
DISPLAY 0.808511 (-2410 7185);
PAINT GREEN (-2410 7185);
DISPLAY INVISIBLE (-2410 7185);
FORCEPROP 1 LAST OFFPAGE TRUE
J 2
(-2410 7105);
DISPLAY 0.808511 (-2410 7105);
PAINT GREEN (-2410 7105);
DISPLAY INVISIBLE (-2410 7105);
FORCEPROP 2 LAST PATH I32
J 2
(-2450 7150);
DISPLAY 1.021277 (-2450 7150);
DISPLAY INVISIBLE (-2450 7150);
FORCEPROP 1 LAST CDS_LMAN_SYM_OUTLINE -50,50,50,-50
J 2
(-2400 7050);
DISPLAY 0.468085 (-2400 7050);
PAINT GREEN (-2400 7050);
DISPLAY INVISIBLE (-2400 7050);
FORCEPROP 2 LAST CDS_LIB cls
J 2
(-2400 7050);
DISPLAY INVISIBLE (-2400 7050);
FORCEPROP 2 LAST $XR0 12F5> 
J 0
(-2345 7050);
DISPLAY 0.638298 (-2345 7050);
PAINT MONO (-2345 7050);
FORCEADD RESISTOR..1
(-4550 7050);
FORCEPROP 1 LAST $LOCATION R298
J 2
(-4700 7050);
DISPLAY 1.212766 (-4700 7050);
PAINT GREEN (-4700 7050);
FORCEPROP 0 LAST CDS_LOCATION R298
J 0
(-4350 7150);
DISPLAY 1.021277 (-4350 7150);
DISPLAY INVISIBLE (-4350 7150);
FORCEPROP 0 LAST $SEC 1
J 0
(-4350 7150);
DISPLAY 0.680851 (-4350 7150);
PAINT MONO (-4350 7150);
DISPLAY INVISIBLE (-4350 7150);
FORCEPROP 0 LAST CDS_SEC 1
J 0
(-4350 7150);
DISPLAY 1.021277 (-4350 7150);
DISPLAY INVISIBLE (-4350 7150);
FORCEPROP 0 LASTPIN (-4650 7050) $PN 1
J 2
(-4660 7060);
DISPLAY 0.680851 (-4660 7060);
PAINT MONO (-4660 7060);
FORCEPROP 0 LASTPIN (-4400 7050) $PN 2
J 0
(-4390 7060);
DISPLAY 0.680851 (-4390 7060);
PAINT MONO (-4390 7060);
FORCEPROP 1 LAST VALUE 33OHM
J 0
(-4350 7050);
DISPLAY 1.234043 (-4350 7050);
PAINT GREEN (-4350 7050);
FORCEPROP 0 LAST PACKAGE 0402
J 0
(-4600 7100);
DISPLAY 1.021277 (-4600 7100);
FORCEPROP 1 LAST PATH I33
J 0
(-4747 7155);
DISPLAY 1.212766 (-4747 7155);
PAINT GREEN (-4747 7155);
DISPLAY INVISIBLE (-4747 7155);
FORCEPROP 1 LAST TOLERANCE 1%
J 0
(-4747 7305);
DISPLAY 1.212766 (-4747 7305);
PAINT GREEN (-4747 7305);
DISPLAY INVISIBLE (-4747 7305);
FORCEPROP 1 LAST CLS_PN G155-133R0-01
J 0
(-4686 7250);
DISPLAY 1.212766 (-4686 7250);
PAINT GREEN (-4686 7250);
DISPLAY INVISIBLE (-4686 7250);
FORCEPROP 2 LAST CDS_LIB passive
J 0
(-4550 7050);
DISPLAY INVISIBLE (-4550 7050);
FORCEPROP 1 LAST CDS_LMAN_SYM_OUTLINE -50,50,100,-50
J 0
(-4550 7050);
DISPLAY 0.468085 (-4550 7050);
PAINT GREEN (-4550 7050);
DISPLAY INVISIBLE (-4550 7050);
FORCEPROP 2 LAST SIGNAL_MODEL DEFAULT_RESISTOR_33OHM_2_1
J 0
(-4700 7250);
DISPLAY 1.021277 (-4700 7250);
DISPLAY INVISIBLE (-4700 7250);
FORCEADD GND_SG..1
(-5100 6200);
FORCEPROP 3 LASTPIN (-5050 6250) SIG_NAME SG\g
J 0
(-5040 6260);
DISPLAY 0.659574 (-5040 6260);
PAINT MONO (-5040 6260);
DISPLAY INVISIBLE (-5040 6260);
FORCEPROP 1 LAST HDL_POWER SG
J 1
(-5045 6105);
DISPLAY 0.808511 (-5045 6105);
PAINT GREEN (-5045 6105);
FORCEPROP 1 LAST PATH I36
J 0
(-5065 6200);
DISPLAY 0.808511 (-5065 6200);
PAINT GREEN (-5065 6200);
DISPLAY INVISIBLE (-5065 6200);
FORCEPROP 1 LAST BODY_TYPE PLUMBING
J 0
(-5085 6185);
DISPLAY 0.808511 (-5085 6185);
PAINT GREEN (-5085 6185);
DISPLAY INVISIBLE (-5085 6185);
FORCEPROP 2 LAST CDS_LIB cls
J 0
(-5100 6200);
DISPLAY INVISIBLE (-5100 6200);
FORCEPROP 1 LAST CDS_LMAN_SYM_OUTLINE 0,0,100,-50
J 0
(-5100 6200);
DISPLAY 0.468085 (-5100 6200);
PAINT GREEN (-5100 6200);
DISPLAY INVISIBLE (-5100 6200);
FORCEADD VCC..1
(-5150 7800);
FORCEPROP 3 LASTPIN (-5100 7750) SIG_NAME XP3R3V_FPGA\g
J 0
(-5090 7760);
DISPLAY 0.659574 (-5090 7760);
PAINT MONO (-5090 7760);
DISPLAY INVISIBLE (-5090 7760);
FORCEPROP 1 LAST HDL_POWER XP3R3V_FPGA
J 1
(-5095 7855);
DISPLAY 1.021277 (-5095 7855);
PAINT GREEN (-5095 7855);
FORCEPROP 0 LAST VOLTAGE 3.3V
J 0
(-5400 7950);
DISPLAY 1.021277 (-5400 7950);
DISPLAY BOTH (-5400 7950);
FORCEPROP 1 LAST PATH I37
J 0
(-5115 7890);
DISPLAY 0.808511 (-5115 7890);
PAINT GREEN (-5115 7890);
DISPLAY INVISIBLE (-5115 7890);
FORCEPROP 1 LAST BODY_TYPE PLUMBING
J 0
(-5195 7757);
DISPLAY 0.340426 (-5195 7757);
PAINT GREEN (-5195 7757);
DISPLAY INVISIBLE (-5195 7757);
FORCEPROP 1 LAST CDS_LMAN_SYM_OUTLINE -250,250,250,-250
J 0
(-5150 7800);
DISPLAY 0.468085 (-5150 7800);
PAINT GREEN (-5150 7800);
DISPLAY INVISIBLE (-5150 7800);
FORCEPROP 2 LAST CDS_LIB cls
J 0
(-5150 7800);
DISPLAY INVISIBLE (-5150 7800);
FORCEADD RESISTOR..2
(-5100 7500);
FORCEPROP 1 LAST LOCATION R296
J 0
(-5050 7350);
DISPLAY 1.212766 (-5050 7350);
PAINT GREEN (-5050 7350);
FORCEPROP 0 LAST $SEC 1
J 0
(-5050 7650);
DISPLAY 0.680851 (-5050 7650);
PAINT MONO (-5050 7650);
DISPLAY INVISIBLE (-5050 7650);
FORCEPROP 0 LAST CDS_SEC 1
J 0
(-5050 7650);
DISPLAY 1.021277 (-5050 7650);
DISPLAY INVISIBLE (-5050 7650);
FORCEPROP 0 LASTPIN (-5100 7600) $PN 1
R 1
J 0
(-5110 7610);
DISPLAY 0.680851 (-5110 7610);
PAINT MONO (-5110 7610);
FORCEPROP 0 LASTPIN (-5100 7350) $PN 2
R 1
J 2
(-5110 7340);
DISPLAY 0.680851 (-5110 7340);
PAINT MONO (-5110 7340);
FORCEPROP 1 LAST VALUE 4.7KOHM
J 0
(-5050 7550);
DISPLAY 1.212766 (-5050 7550);
PAINT GREEN (-5050 7550);
FORCEPROP 0 LAST PACKAGE 0402
J 0
(-5050 7700);
DISPLAY 1.021277 (-5050 7700);
FORCEPROP 1 LAST PATH I38
J 0
(-5297 7605);
DISPLAY 1.212766 (-5297 7605);
PAINT GREEN (-5297 7605);
DISPLAY INVISIBLE (-5297 7605);
FORCEPROP 1 LAST TOLERANCE 1%
J 0
(-5297 7755);
DISPLAY 1.212766 (-5297 7755);
PAINT GREEN (-5297 7755);
DISPLAY INVISIBLE (-5297 7755);
FORCEPROP 1 LAST CLS_PN G155-14701-01
J 0
(-5236 7700);
DISPLAY 1.212766 (-5236 7700);
PAINT GREEN (-5236 7700);
DISPLAY INVISIBLE (-5236 7700);
FORCEPROP 1 LAST CDS_LMAN_SYM_OUTLINE -50,50,50,-100
J 0
(-5100 7500);
DISPLAY 0.468085 (-5100 7500);
PAINT GREEN (-5100 7500);
DISPLAY INVISIBLE (-5100 7500);
FORCEPROP 2 LAST CDS_LIB passive
J 0
(-5100 7500);
DISPLAY INVISIBLE (-5100 7500);
FORCEADD RESISTOR..2
(-5050 6600);
FORCEPROP 1 LAST LOCATION R297
J 0
(-5000 6450);
DISPLAY 1.212766 (-5000 6450);
PAINT GREEN (-5000 6450);
FORCEPROP 0 LAST $SEC 1
J 0
(-5000 6750);
DISPLAY 0.680851 (-5000 6750);
PAINT MONO (-5000 6750);
DISPLAY INVISIBLE (-5000 6750);
FORCEPROP 0 LAST CDS_SEC 1
J 0
(-5000 6750);
DISPLAY 1.021277 (-5000 6750);
DISPLAY INVISIBLE (-5000 6750);
FORCEPROP 0 LASTPIN (-5050 6700) $PN 1
R 1
J 0
(-5060 6710);
DISPLAY 0.680851 (-5060 6710);
PAINT MONO (-5060 6710);
FORCEPROP 0 LASTPIN (-5050 6450) $PN 2
R 1
J 2
(-5060 6440);
DISPLAY 0.680851 (-5060 6440);
PAINT MONO (-5060 6440);
FORCEPROP 0 LAST PACKAGE 0402
J 0
(-5000 6800);
DISPLAY 1.021277 (-5000 6800);
FORCEPROP 0 LAST NO_ASSY TRUE
J 0
(-4950 6550);
DISPLAY 0.808511 (-4950 6550);
DISPLAY BOTH (-4950 6550);
FORCEPROP 1 LAST VALUE 4.7KOHM
J 0
(-5000 6650);
DISPLAY 1.212766 (-5000 6650);
PAINT GREEN (-5000 6650);
FORCEPROP 1 LAST PATH I39
J 0
(-5247 6705);
DISPLAY 1.212766 (-5247 6705);
PAINT GREEN (-5247 6705);
DISPLAY INVISIBLE (-5247 6705);
FORCEPROP 1 LAST TOLERANCE 1%
J 0
(-5247 6855);
DISPLAY 1.212766 (-5247 6855);
PAINT GREEN (-5247 6855);
DISPLAY INVISIBLE (-5247 6855);
FORCEPROP 2 LAST CDS_LIB passive
J 0
(-5050 6600);
DISPLAY INVISIBLE (-5050 6600);
FORCEPROP 1 LAST CDS_LMAN_SYM_OUTLINE -50,50,50,-100
J 0
(-5050 6600);
DISPLAY 0.468085 (-5050 6600);
PAINT GREEN (-5050 6600);
DISPLAY INVISIBLE (-5050 6600);
FORCEPROP 1 LAST CLS_PN G155-14701-01
J 0
(-5186 6800);
DISPLAY 1.212766 (-5186 6800);
PAINT GREEN (-5186 6800);
DISPLAY INVISIBLE (-5186 6800);
FORCEADD RESISTOR..2
(-9950 9550);
FORCEPROP 1 LAST $LOCATION R65
J 0
(-9900 9400);
DISPLAY 1.212766 (-9900 9400);
PAINT GREEN (-9900 9400);
FORCEPROP 0 LAST CDS_LOCATION R65
J 0
(-9900 9650);
DISPLAY 1.021277 (-9900 9650);
DISPLAY INVISIBLE (-9900 9650);
FORCEPROP 0 LAST $SEC 1
J 0
(-9900 9650);
DISPLAY 0.680851 (-9900 9650);
PAINT MONO (-9900 9650);
DISPLAY INVISIBLE (-9900 9650);
FORCEPROP 0 LAST CDS_SEC 1
J 0
(-9900 9650);
DISPLAY 1.021277 (-9900 9650);
DISPLAY INVISIBLE (-9900 9650);
FORCEPROP 0 LASTPIN (-9950 9650) $PN 1
R 1
J 0
(-9960 9660);
DISPLAY 0.680851 (-9960 9660);
PAINT MONO (-9960 9660);
FORCEPROP 0 LASTPIN (-9950 9400) $PN 2
R 1
J 2
(-9960 9390);
DISPLAY 0.680851 (-9960 9390);
PAINT MONO (-9960 9390);
FORCEPROP 1 LAST VALUE 4.7KOHM
J 0
(-9900 9600);
DISPLAY 0.978723 (-9900 9600);
PAINT GREEN (-9900 9600);
FORCEPROP 0 LAST PACKAGE 0402
J 0
(-9900 9700);
DISPLAY 1.021277 (-9900 9700);
FORCEPROP 1 LAST PATH I4
J 0
(-10147 9655);
DISPLAY 1.212766 (-10147 9655);
PAINT GREEN (-10147 9655);
DISPLAY INVISIBLE (-10147 9655);
FORCEPROP 1 LAST TOLERANCE 1%
J 0
(-10147 9805);
DISPLAY 1.212766 (-10147 9805);
PAINT GREEN (-10147 9805);
DISPLAY INVISIBLE (-10147 9805);
FORCEPROP 1 LAST CLS_PN G155-14701-01
J 0
(-10086 9750);
DISPLAY 1.212766 (-10086 9750);
PAINT GREEN (-10086 9750);
DISPLAY INVISIBLE (-10086 9750);
FORCEPROP 1 LAST CDS_LMAN_SYM_OUTLINE -50,50,50,-100
J 0
(-9950 9550);
DISPLAY 0.468085 (-9950 9550);
PAINT GREEN (-9950 9550);
DISPLAY INVISIBLE (-9950 9550);
FORCEPROP 2 LAST CDS_LIB passive
J 0
(-9950 9550);
DISPLAY INVISIBLE (-9950 9550);
FORCEADD RESISTOR..1
(-4550 6950);
FORCEPROP 1 LAST $LOCATION R299
J 2
(-4700 6950);
DISPLAY 1.212766 (-4700 6950);
PAINT GREEN (-4700 6950);
FORCEPROP 0 LAST CDS_LOCATION R299
J 0
(-4350 7050);
DISPLAY 1.021277 (-4350 7050);
DISPLAY INVISIBLE (-4350 7050);
FORCEPROP 0 LAST $SEC 1
J 0
(-4350 7050);
DISPLAY 0.680851 (-4350 7050);
PAINT MONO (-4350 7050);
DISPLAY INVISIBLE (-4350 7050);
FORCEPROP 0 LAST CDS_SEC 1
J 0
(-4350 7050);
DISPLAY 1.021277 (-4350 7050);
DISPLAY INVISIBLE (-4350 7050);
FORCEPROP 0 LASTPIN (-4650 6950) $PN 1
J 2
(-4660 6960);
DISPLAY 0.680851 (-4660 6960);
PAINT MONO (-4660 6960);
FORCEPROP 0 LASTPIN (-4400 6950) $PN 2
J 0
(-4390 6960);
DISPLAY 0.680851 (-4390 6960);
PAINT MONO (-4390 6960);
FORCEPROP 1 LAST VALUE 33OHM
J 0
(-4350 6950);
DISPLAY 1.234043 (-4350 6950);
PAINT GREEN (-4350 6950);
FORCEPROP 0 LAST PACKAGE 0402
J 0
(-4600 6850);
DISPLAY 1.021277 (-4600 6850);
FORCEPROP 1 LAST PATH I40
J 0
(-4747 7055);
DISPLAY 1.212766 (-4747 7055);
PAINT GREEN (-4747 7055);
DISPLAY INVISIBLE (-4747 7055);
FORCEPROP 1 LAST TOLERANCE 1%
J 0
(-4747 7205);
DISPLAY 1.212766 (-4747 7205);
PAINT GREEN (-4747 7205);
DISPLAY INVISIBLE (-4747 7205);
FORCEPROP 1 LAST CLS_PN G155-133R0-01
J 0
(-4686 7150);
DISPLAY 1.212766 (-4686 7150);
PAINT GREEN (-4686 7150);
DISPLAY INVISIBLE (-4686 7150);
FORCEPROP 2 LAST SIGNAL_MODEL DEFAULT_RESISTOR_33OHM_2_1
J 0
(-4700 7150);
DISPLAY 1.021277 (-4700 7150);
DISPLAY INVISIBLE (-4700 7150);
FORCEPROP 1 LAST CDS_LMAN_SYM_OUTLINE -50,50,100,-50
J 0
(-4550 6950);
DISPLAY 0.468085 (-4550 6950);
PAINT GREEN (-4550 6950);
DISPLAY INVISIBLE (-4550 6950);
FORCEPROP 2 LAST CDS_LIB passive
J 0
(-4550 6950);
DISPLAY INVISIBLE (-4550 6950);
FORCEADD RESISTOR..2
(-3800 7500);
FORCEPROP 1 LAST $LOCATION R300
J 0
(-3750 7350);
DISPLAY 1.212766 (-3750 7350);
PAINT GREEN (-3750 7350);
FORCEPROP 0 LAST CDS_LOCATION R300
J 0
(-3750 7650);
DISPLAY 1.021277 (-3750 7650);
DISPLAY INVISIBLE (-3750 7650);
FORCEPROP 0 LAST $SEC 1
J 0
(-3750 7650);
DISPLAY 0.680851 (-3750 7650);
PAINT MONO (-3750 7650);
DISPLAY INVISIBLE (-3750 7650);
FORCEPROP 0 LAST CDS_SEC 1
J 0
(-3750 7650);
DISPLAY 1.021277 (-3750 7650);
DISPLAY INVISIBLE (-3750 7650);
FORCEPROP 0 LASTPIN (-3800 7600) $PN 1
R 1
J 0
(-3810 7610);
DISPLAY 0.680851 (-3810 7610);
PAINT MONO (-3810 7610);
FORCEPROP 0 LASTPIN (-3800 7350) $PN 2
R 1
J 2
(-3810 7340);
DISPLAY 0.680851 (-3810 7340);
PAINT MONO (-3810 7340);
FORCEPROP 0 LAST PACKAGE 0402
J 0
(-3750 7700);
DISPLAY 1.021277 (-3750 7700);
FORCEPROP 1 LAST VALUE 4.7KOHM
J 0
(-3750 7550);
DISPLAY 1.212766 (-3750 7550);
PAINT GREEN (-3750 7550);
FORCEPROP 1 LAST PATH I41
J 0
(-3997 7605);
DISPLAY 1.212766 (-3997 7605);
PAINT GREEN (-3997 7605);
DISPLAY INVISIBLE (-3997 7605);
FORCEPROP 1 LAST TOLERANCE 1%
J 0
(-3997 7755);
DISPLAY 1.212766 (-3997 7755);
PAINT GREEN (-3997 7755);
DISPLAY INVISIBLE (-3997 7755);
FORCEPROP 2 LAST CDS_LIB passive
J 0
(-3800 7500);
DISPLAY INVISIBLE (-3800 7500);
FORCEPROP 1 LAST CDS_LMAN_SYM_OUTLINE -50,50,50,-100
J 0
(-3800 7500);
DISPLAY 0.468085 (-3800 7500);
PAINT GREEN (-3800 7500);
DISPLAY INVISIBLE (-3800 7500);
FORCEPROP 1 LAST CLS_PN G155-14701-01
J 0
(-3936 7700);
DISPLAY 1.212766 (-3936 7700);
PAINT GREEN (-3936 7700);
DISPLAY INVISIBLE (-3936 7700);
FORCEADD VCC..1
(-3850 7800);
FORCEPROP 3 LASTPIN (-3800 7750) SIG_NAME XP3R3V_FPGA\g
J 0
(-3790 7760);
DISPLAY 0.659574 (-3790 7760);
PAINT MONO (-3790 7760);
DISPLAY INVISIBLE (-3790 7760);
FORCEPROP 1 LAST HDL_POWER XP3R3V_FPGA
J 1
(-3795 7855);
DISPLAY 1.021277 (-3795 7855);
PAINT GREEN (-3795 7855);
FORCEPROP 0 LAST VOLTAGE 3.3V
J 0
(-4100 7950);
DISPLAY 1.021277 (-4100 7950);
DISPLAY BOTH (-4100 7950);
FORCEPROP 1 LAST PATH I42
J 0
(-3815 7890);
DISPLAY 0.808511 (-3815 7890);
PAINT GREEN (-3815 7890);
DISPLAY INVISIBLE (-3815 7890);
FORCEPROP 1 LAST BODY_TYPE PLUMBING
J 0
(-3895 7757);
DISPLAY 0.340426 (-3895 7757);
PAINT GREEN (-3895 7757);
DISPLAY INVISIBLE (-3895 7757);
FORCEPROP 1 LAST CDS_LMAN_SYM_OUTLINE -250,250,250,-250
J 0
(-3850 7800);
DISPLAY 0.468085 (-3850 7800);
PAINT GREEN (-3850 7800);
DISPLAY INVISIBLE (-3850 7800);
FORCEPROP 2 LAST CDS_LIB cls
J 0
(-3850 7800);
DISPLAY INVISIBLE (-3850 7800);
FORCEADD OFFPAGE_OUT..1
(-2400 6950);
FORCEPROP 1 LAST BODY_TYPE COMMENT
J 0
(-2390 7085);
DISPLAY 0.808511 (-2390 7085);
PAINT GREEN (-2390 7085);
DISPLAY INVISIBLE (-2390 7085);
FORCEPROP 1 LAST OFFPAGE TRUE
J 0
(-2390 7005);
DISPLAY 0.808511 (-2390 7005);
PAINT GREEN (-2390 7005);
DISPLAY INVISIBLE (-2390 7005);
FORCEPROP 2 LAST PATH I43
J 0
(-2350 7050);
DISPLAY 1.021277 (-2350 7050);
DISPLAY INVISIBLE (-2350 7050);
FORCEPROP 2 LAST CDS_LIB cls
J 0
(-2400 6950);
DISPLAY INVISIBLE (-2400 6950);
FORCEPROP 1 LAST CDS_LMAN_SYM_OUTLINE -50,50,50,-50
J 0
(-2400 6950);
DISPLAY 0.468085 (-2400 6950);
PAINT GREEN (-2400 6950);
DISPLAY INVISIBLE (-2400 6950);
FORCEPROP 2 LAST $XR0 12F5< 
J 0
(-2345 6950);
DISPLAY 0.638298 (-2345 6950);
PAINT MONO (-2345 6950);
FORCEADD SHT31A_DIS_B10KS_DFN8..1
R 2
(-6650 9150);
FORCEPROP 1 LAST $LOCATION U27
J 2
(-6650 9400);
DISPLAY 1.212766 (-6650 9400);
PAINT GREEN (-6650 9400);
FORCEPROP 0 LAST CDS_LOCATION U27
J 0
(-6650 9500);
DISPLAY 1.021277 (-6650 9500);
DISPLAY INVISIBLE (-6650 9500);
FORCEPROP 0 LAST $SEC 1
J 0
(-6650 9500);
DISPLAY 0.680851 (-6650 9500);
PAINT MONO (-6650 9500);
DISPLAY INVISIBLE (-6650 9500);
FORCEPROP 0 LAST CDS_SEC 1
J 0
(-6650 9500);
DISPLAY 1.021277 (-6650 9500);
DISPLAY INVISIBLE (-6650 9500);
FORCEPROP 0 LASTPIN (-7750 8550) $PN 2
J 2
(-7760 8560);
DISPLAY 0.680851 (-7760 8560);
PAINT MONO (-7760 8560);
FORCEPROP 0 LASTPIN (-6550 8450) $PN 3
J 0
(-6540 8460);
DISPLAY 0.680851 (-6540 8460);
PAINT MONO (-6540 8460);
FORCEPROP 0 LASTPIN (-7750 8750) $PN 7
J 2
(-7760 8760);
DISPLAY 0.680851 (-7760 8760);
PAINT MONO (-7760 8760);
FORCEPROP 0 LASTPIN (-6550 8750) $PN 6
J 0
(-6540 8760);
DISPLAY 0.680851 (-6540 8760);
PAINT MONO (-6540 8760);
FORCEPROP 0 LASTPIN (-7750 8950) $PN 4
J 2
(-7760 8960);
DISPLAY 0.680851 (-7760 8960);
PAINT MONO (-7760 8960);
FORCEPROP 0 LASTPIN (-7750 9050) $PN 1
J 2
(-7760 9060);
DISPLAY 0.680851 (-7760 9060);
PAINT MONO (-7760 9060);
FORCEPROP 0 LASTPIN (-7750 8250) $PN 9
J 2
(-7760 8260);
DISPLAY 0.680851 (-7760 8260);
PAINT MONO (-7760 8260);
FORCEPROP 0 LASTPIN (-6550 9050) $PN 5
J 0
(-6540 9060);
DISPLAY 0.680851 (-6540 9060);
PAINT MONO (-6540 9060);
FORCEPROP 0 LASTPIN (-7750 8350) $PN 8
J 2
(-7760 8360);
DISPLAY 0.680851 (-7760 8360);
PAINT MONO (-7760 8360);
FORCEPROP 1 LAST CLS_PN A222-00001-FB
J 2
(-6650 9200);
DISPLAY 1.212766 (-6650 9200);
PAINT GREEN (-6650 9200);
FORCEPROP 1 LAST VALUE SHT31A-DIS-B10KS
J 2
(-6650 9300);
DISPLAY 1.212766 (-6650 9300);
PAINT GREEN (-6650 9300);
FORCEPROP 1 LAST PATH I44
J 2
(-6700 9200);
DISPLAY 1.212766 (-6700 9200);
PAINT GREEN (-6700 9200);
DISPLAY INVISIBLE (-6700 9200);
FORCEPROP 1 LAST CDS_LMAN_SYM_OUTLINE 0,0,1000,-1000
J 2
(-6650 9150);
DISPLAY 0.468085 (-6650 9150);
PAINT GREEN (-6650 9150);
DISPLAY INVISIBLE (-6650 9150);
FORCEPROP 2 LAST CDS_LIB analog
J 2
(-6650 9150);
DISPLAY INVISIBLE (-6650 9150);
FORCEADD OFFPAGE_IN..1
(-6450 7050);
FORCEPROP 2 LAST CDS_LIB cls
J 0
(-6450 7050);
DISPLAY INVISIBLE (-6450 7050);
FORCEPROP 2 LAST PATH I45
J 0
(-6400 7150);
DISPLAY 1.021277 (-6400 7150);
DISPLAY INVISIBLE (-6400 7150);
FORCEPROP 1 LAST CDS_LMAN_SYM_OUTLINE -50,50,50,-50
J 0
(-6450 7050);
DISPLAY 0.468085 (-6450 7050);
PAINT GREEN (-6450 7050);
DISPLAY INVISIBLE (-6450 7050);
FORCEPROP 1 LAST BODY_TYPE COMMENT
J 0
(-6440 7185);
DISPLAY 0.808511 (-6440 7185);
PAINT GREEN (-6440 7185);
DISPLAY INVISIBLE (-6440 7185);
FORCEPROP 1 LAST OFFPAGE TRUE
J 0
(-6440 7105);
DISPLAY 0.808511 (-6440 7105);
PAINT GREEN (-6440 7105);
DISPLAY INVISIBLE (-6440 7105);
FORCEPROP 2 LAST $XR0 25E6<> 
J 0
(-6664 7050);
DISPLAY 0.638298 (-6664 7050);
PAINT MONO (-6664 7050);
FORCEADD OFFPAGE_OUT..1
R 2
(-6450 6950);
FORCEPROP 1 LAST OFFPAGE TRUE
J 2
(-6460 7005);
DISPLAY 0.808511 (-6460 7005);
PAINT GREEN (-6460 7005);
DISPLAY INVISIBLE (-6460 7005);
FORCEPROP 1 LAST BODY_TYPE COMMENT
J 2
(-6460 7085);
DISPLAY 0.808511 (-6460 7085);
PAINT GREEN (-6460 7085);
DISPLAY INVISIBLE (-6460 7085);
FORCEPROP 1 LAST CDS_LMAN_SYM_OUTLINE -50,50,50,-50
J 2
(-6450 6950);
DISPLAY 0.468085 (-6450 6950);
PAINT GREEN (-6450 6950);
DISPLAY INVISIBLE (-6450 6950);
FORCEPROP 2 LAST PATH I46
J 2
(-6500 7050);
DISPLAY 1.021277 (-6500 7050);
DISPLAY INVISIBLE (-6500 7050);
FORCEPROP 2 LAST CDS_LIB cls
J 2
(-6450 6950);
DISPLAY INVISIBLE (-6450 6950);
FORCEPROP 2 LAST $XR0 25E6<> 
J 0
(-6664 6950);
DISPLAY 0.638298 (-6664 6950);
PAINT MONO (-6664 6950);
FORCEADD GND_SG..1
(-9150 7300);
FORCEPROP 3 LASTPIN (-9100 7350) SIG_NAME SG\g
J 0
(-9090 7360);
DISPLAY 0.659574 (-9090 7360);
PAINT MONO (-9090 7360);
DISPLAY INVISIBLE (-9090 7360);
FORCEPROP 1 LAST HDL_POWER SG
J 1
(-9095 7205);
DISPLAY 0.808511 (-9095 7205);
PAINT GREEN (-9095 7205);
FORCEPROP 1 LAST PATH I6
J 0
(-9115 7300);
DISPLAY 0.808511 (-9115 7300);
PAINT GREEN (-9115 7300);
DISPLAY INVISIBLE (-9115 7300);
FORCEPROP 1 LAST BODY_TYPE PLUMBING
J 0
(-9135 7285);
DISPLAY 0.808511 (-9135 7285);
PAINT GREEN (-9135 7285);
DISPLAY INVISIBLE (-9135 7285);
FORCEPROP 2 LAST CDS_LIB cls
J 0
(-9150 7300);
DISPLAY INVISIBLE (-9150 7300);
FORCEPROP 1 LAST CDS_LMAN_SYM_OUTLINE 0,0,100,-50
J 0
(-9150 7300);
DISPLAY 0.468085 (-9150 7300);
PAINT GREEN (-9150 7300);
DISPLAY INVISIBLE (-9150 7300);
FORCEADD RESISTOR..2
(-9100 7600);
FORCEPROP 1 LAST $LOCATION R69
J 0
(-9050 7450);
DISPLAY 1.212766 (-9050 7450);
PAINT GREEN (-9050 7450);
FORCEPROP 0 LAST CDS_LOCATION R69
J 0
(-9050 7750);
DISPLAY 1.021277 (-9050 7750);
DISPLAY INVISIBLE (-9050 7750);
FORCEPROP 0 LAST $SEC 1
J 0
(-9050 7750);
DISPLAY 0.680851 (-9050 7750);
PAINT MONO (-9050 7750);
DISPLAY INVISIBLE (-9050 7750);
FORCEPROP 0 LAST CDS_SEC 1
J 0
(-9050 7750);
DISPLAY 1.021277 (-9050 7750);
DISPLAY INVISIBLE (-9050 7750);
FORCEPROP 0 LASTPIN (-9100 7700) $PN 1
R 1
J 0
(-9110 7710);
DISPLAY 0.680851 (-9110 7710);
PAINT MONO (-9110 7710);
FORCEPROP 0 LASTPIN (-9100 7450) $PN 2
R 1
J 2
(-9110 7440);
DISPLAY 0.680851 (-9110 7440);
PAINT MONO (-9110 7440);
FORCEPROP 1 LAST VALUE 1KOHM
J 0
(-9050 7650);
DISPLAY 1.212766 (-9050 7650);
PAINT GREEN (-9050 7650);
FORCEPROP 0 LAST PACKAGE 0402
J 0
(-9000 7550);
DISPLAY 1.021277 (-9000 7550);
FORCEPROP 1 LAST PATH I7
J 0
(-9297 7705);
DISPLAY 1.212766 (-9297 7705);
PAINT GREEN (-9297 7705);
DISPLAY INVISIBLE (-9297 7705);
FORCEPROP 1 LAST TOLERANCE 1%
J 0
(-9297 7855);
DISPLAY 1.212766 (-9297 7855);
PAINT GREEN (-9297 7855);
DISPLAY INVISIBLE (-9297 7855);
FORCEPROP 2 LAST CDS_LIB passive
J 0
(-9100 7600);
DISPLAY INVISIBLE (-9100 7600);
FORCEPROP 1 LAST CDS_LMAN_SYM_OUTLINE -50,50,50,-100
J 0
(-9100 7600);
DISPLAY 0.468085 (-9100 7600);
PAINT GREEN (-9100 7600);
DISPLAY INVISIBLE (-9100 7600);
FORCEPROP 1 LAST CLS_PN G155-11001-01
J 0
(-9236 7800);
DISPLAY 1.212766 (-9236 7800);
PAINT GREEN (-9236 7800);
DISPLAY INVISIBLE (-9236 7800);
FORCEADD RESISTOR..2
(-9100 8200);
FORCEPROP 1 LAST $LOCATION R68
J 0
(-9050 8050);
DISPLAY 1.212766 (-9050 8050);
PAINT GREEN (-9050 8050);
FORCEPROP 0 LAST CDS_LOCATION R68
J 0
(-9050 8350);
DISPLAY 1.021277 (-9050 8350);
DISPLAY INVISIBLE (-9050 8350);
FORCEPROP 0 LAST $SEC 1
J 0
(-9050 8350);
DISPLAY 0.680851 (-9050 8350);
PAINT MONO (-9050 8350);
DISPLAY INVISIBLE (-9050 8350);
FORCEPROP 0 LAST CDS_SEC 1
J 0
(-9050 8350);
DISPLAY 1.021277 (-9050 8350);
DISPLAY INVISIBLE (-9050 8350);
FORCEPROP 0 LASTPIN (-9100 8300) $PN 1
R 1
J 0
(-9110 8360);
DISPLAY 0.680851 (-9110 8360);
PAINT MONO (-9110 8360);
FORCEPROP 0 LASTPIN (-9100 8050) $PN 2
R 1
J 2
(-9110 8040);
DISPLAY 0.680851 (-9110 8040);
PAINT MONO (-9110 8040);
FORCEPROP 0 LAST NO_ASSY TRUE
J 0
(-8900 8100);
DISPLAY 0.808511 (-8900 8100);
DISPLAY BOTH (-8900 8100);
FORCEPROP 1 LAST VALUE 4.7KOHM
J 0
(-9050 8250);
DISPLAY 1.212766 (-9050 8250);
PAINT GREEN (-9050 8250);
FORCEPROP 0 LAST PACKAGE 0402
J 0
(-9050 8150);
DISPLAY 1.021277 (-9050 8150);
FORCEPROP 1 LAST PATH I8
J 0
(-9297 8305);
DISPLAY 1.212766 (-9297 8305);
PAINT GREEN (-9297 8305);
DISPLAY INVISIBLE (-9297 8305);
FORCEPROP 1 LAST TOLERANCE 1%
J 0
(-9297 8455);
DISPLAY 1.212766 (-9297 8455);
PAINT GREEN (-9297 8455);
DISPLAY INVISIBLE (-9297 8455);
FORCEPROP 2 LAST CDS_LIB passive
J 0
(-9100 8200);
DISPLAY INVISIBLE (-9100 8200);
FORCEPROP 1 LAST CDS_LMAN_SYM_OUTLINE -50,50,50,-100
J 0
(-9100 8200);
DISPLAY 0.468085 (-9100 8200);
PAINT GREEN (-9100 8200);
DISPLAY INVISIBLE (-9100 8200);
FORCEPROP 1 LAST CLS_PN G155-14701-01
J 0
(-9236 8400);
DISPLAY 1.212766 (-9236 8400);
PAINT GREEN (-9236 8400);
DISPLAY INVISIBLE (-9236 8400);
FORCEADD SHEET_A1..1
(900 2050);
FORCEPROP 2 LAST CUSTOM_TXT_CDS <XR_PAGE_TITLE>
J 0
(-14670 13400);
DISPLAY 0.638298 (-14670 13400);
PAINT PINK (-14670 13400);
FORCEPROP 1 LAST CUSTOM_TXT_CDS <DOCNO>
J 0
(-1150 2435);
DISPLAY 0.978723 (-1150 2435);
FORCEPROP 1 LAST CUSTOM_TXT_CDS <CON_PAGE_NUM>
J 0
(-1255 2100);
DISPLAY 0.978723 (-1255 2100);
FORCEPROP 1 LAST CUSTOM_TXT_CDS <DATE>
J 0
(200 2225);
DISPLAY 0.978723 (200 2225);
FORCEPROP 1 LAST CUSTOM_TXT_CDS <TITLE>
J 1
(-885 2680);
DISPLAY 0.978723 (-885 2680);
FORCEPROP 1 LAST CUSTOM_TXT_CDS <DESIGNER>
J 0
(200 2650);
DISPLAY 0.978723 (200 2650);
FORCEPROP 1 LAST CUSTOM_TXT_CDS <CON_TOTAL_PAGES>
J 0
(-945 2100);
DISPLAY 0.808511 (-945 2100);
FORCEPROP 1 LAST CUSTOM_TXT_CDS <ASSY_PN>
J 0
(-1150 2225);
DISPLAY 0.978723 (-1150 2225);
FORCEPROP 1 LAST CUSTOM_TXT_CDS <DOCREV>
J 0
(200 2425);
DISPLAY 0.978723 (200 2425);
FORCEPROP 1 LAST TITLE HUMIDITY_SENSOR
J 0
(-1600 2900);
DISPLAY 3.042553 (-1600 2900);
PAINT GREEN (-1600 2900);
FORCEPROP 1 LAST COMMENT_BODY TRUE
J 0
(910 2105);
DISPLAY 0.808511 (910 2105);
DISPLAY INVISIBLE (910 2105);
FORCEPROP 2 LAST PAGE_BORDER TRUE
J 0
(-14670 13400);
DISPLAY 0.638298 (-14670 13400);
PAINT PINK (-14670 13400);
DISPLAY INVISIBLE (-14670 13400);
FORCEPROP 1 LAST CDS_LMAN_SYM_OUTLINE -15850,11500,200,-200
J 0
(900 2050);
DISPLAY 0.468085 (900 2050);
PAINT GREEN (900 2050);
DISPLAY INVISIBLE (900 2050);
FORCEPROP 2 LAST CDS_LIB cls
J 0
(900 2050);
DISPLAY INVISIBLE (900 2050);
FORCEPROP 2 LAST CDS_XR_PAGE_TITLE CR-18 : @TIMECARD_LIB.TIMECARD(SCH_1):PAGE18
J 0
(-14670 13400);
DISPLAY 0.638298 (-14670 13400);
PAINT PINK (-14670 13400);
DISPLAY INVISIBLE (-14670 13400);
WIRE 16 -1 (-9100 7350)(-9100 7450);
WIRE 16 -1 (-3800 7600)(-3800 7750);
WIRE 16 -1 (-5100 7600)(-5100 7750);
WIRE 16 -1 (-5050 6250)(-5050 6450);
WIRE 16 -1 (-9100 8300)(-9100 8400);
WIRE 16 -1 (-7750 8250)(-7900 8250);
WIRE 16 -1 (-7900 8350)(-7900 8250);
WIRE 16 -1 (-7900 8250)(-7900 8100);
WIRE 16 -1 (-7900 8750)(-7900 8350);
WIRE 16 -1 (-7900 8350)(-7750 8350);
WIRE 16 -1 (-7750 8750)(-7900 8750);
WIRE 16 -1 (-4300 8600)(-4300 8350);
WIRE 16 -1 (-4300 8350)(-5200 8350);
WIRE 16 -1 (-5200 8600)(-5200 8350);
WIRE 16 -1 (-5650 8350)(-5200 8350);
WIRE 16 -1 (-5650 8250)(-5650 8350);
WIRE 16 -1 (-5650 8600)(-5650 8350);
WIRE 16 -1 (-4000 9050)(-4000 9200);
WIRE 16 -1 (-4300 9050)(-4000 9050);
WIRE 16 -1 (-4300 9050)(-4300 8850);
WIRE 16 -1 (-4300 9050)(-4550 9050);
WIRE 16 -1 (-9950 9650)(-9950 9850);
WIRE 16 -1 (-9950 9850)(-10400 9850);
WIRE 16 -1 (-10400 9850)(-10400 9950);
WIRE 16 -1 (-10400 9650)(-10400 9850);
WIRE 16 -1 (-6300 8450)(-6300 6950);
WIRE 16 -1 (-6550 8450)(-6300 8450);
WIRE 16 -1 (-4650 6950)(-6300 6950);
FORCEPROP 2 LAST SIG_NAME R_SHT3X_ALERT_N
J 0
(-6110 6960);
DISPLAY 1.021277 (-6110 6960);
WIRE 16 -1 (-6300 6950)(-6400 6950);
WIRE 16 -1 (-4400 6950)(-3800 6950);
WIRE 16 -1 (-3800 6950)(-2450 6950);
FORCEPROP 2 LAST SIG_NAME FPGA_IN_SHT3X_ALERT_N
J 0
(-3510 6960);
DISPLAY 1.021277 (-3510 6960);
WIRE 16 -1 (-3800 7350)(-3800 6950);
WIRE 16 -1 (-6550 8750)(-6200 8750);
WIRE 16 -1 (-6200 8750)(-6200 7050);
WIRE 16 -1 (-5100 7050)(-6200 7050);
FORCEPROP 2 LAST SIG_NAME R_SHT3X_RST_N
J 0
(-6110 7060);
DISPLAY 1.021277 (-6110 7060);
WIRE 16 -1 (-6200 7050)(-6400 7050);
WIRE 16 -1 (-5100 7350)(-5100 7050);
WIRE 16 -1 (-5100 7050)(-5050 7050);
WIRE 16 -1 (-5050 7050)(-4650 7050);
WIRE 16 -1 (-5050 7050)(-5050 6700);
WIRE 16 -1 (-9150 8950)(-7750 8950);
FORCEPROP 2 LAST SIG_NAME R_SHT3X_I2C_SCL
J 0
(-8610 8960);
DISPLAY 1.021277 (-8610 8960);
WIRE 16 -1 (-9150 9050)(-7750 9050);
FORCEPROP 2 LAST SIG_NAME R_SHT3X_I2C_SDA
J 0
(-8610 9060);
DISPLAY 1.021277 (-8610 9060);
WIRE 16 -1 (-5200 8850)(-5200 9050);
WIRE 16 -1 (-4950 9050)(-5200 9050);
WIRE 16 -1 (-5650 9050)(-5200 9050);
WIRE 16 -1 (-5650 8850)(-5650 9050);
WIRE 16 -1 (-6550 9050)(-5650 9050);
FORCEPROP 2 LAST SIG_NAME VDD3V3_SHT31A
J 0
(-6410 9060);
DISPLAY 1.021277 (-6410 9060);
WIRE 16 -1 (-4400 7050)(-2450 7050);
FORCEPROP 2 LAST SIG_NAME FPGA_OUT_SHT3X_RST_N
J 0
(-3510 7060);
DISPLAY 1.021277 (-3510 7060);
WIRE 16 -1 (-9100 7700)(-9100 7850);
WIRE 16 -1 (-8100 7850)(-9100 7850);
FORCEPROP 2 LAST SIG_NAME SHT3X_ADDR
J 0
(-8810 7860);
DISPLAY 1.021277 (-8810 7860);
WIRE 16 -1 (-9100 8050)(-9100 7850);
WIRE 16 -1 (-8100 8550)(-8100 7850);
WIRE 16 -1 (-7750 8550)(-8100 8550);
WIRE 16 -1 (-10400 9400)(-10400 9050);
WIRE 16 -1 (-10400 9050)(-9400 9050);
WIRE 16 -1 (-11700 9050)(-10400 9050);
FORCEPROP 2 LAST SIG_NAME SHT3X_I2C_SDA
J 0
(-11610 9060);
DISPLAY 1.021277 (-11610 9060);
WIRE 16 -1 (-9950 9400)(-9950 8950);
WIRE 16 -1 (-9950 8950)(-9400 8950);
WIRE 16 -1 (-11700 8950)(-9950 8950);
FORCEPROP 2 LAST SIG_NAME SHT3X_I2C_SCL
J 0
(-11610 8960);
DISPLAY 1.021277 (-11610 8960);
DOT 1 (-6300 6950);
DOT 1 (-6200 7050);
DOT 1 (-5200 9050);
DOT 1 (-5650 9050);
DOT 1 (-7900 8250);
DOT 1 (-5100 7050);
DOT 1 (-3800 6950);
DOT 1 (-7900 8350);
DOT 1 (-5050 7050);
DOT 1 (-9950 8950);
DOT 1 (-10400 9850);
DOT 1 (-10400 9050);
DOT 1 (-9100 7850);
DOT 1 (-4300 9050);
DOT 1 (-5200 8350);
DOT 1 (-5650 8350);
FORCENOTE
LOW : I2C ADDR = 0X44 
(-8450 7400) 0;
DISPLAY LEFT (-8450 7400);
DISPLAY 1.595745 (-8450 7400);
FORCENOTE
HIGH: I2C ADDR = 0X45 
(-8450 7550) 0;
DISPLAY LEFT (-8450 7550);
DISPLAY 1.595745 (-8450 7550);
FORCENOTE
HUMIDITY_SENSOR
(-8600 12150) 0;
DISPLAY LEFT (-8600 12150);
DISPLAY 4.914894 (-8600 12150);
QUIT
